# T6G (Grand Teton) — schematic netlist excerpt (pin names and nets, part order shuffled) for the footprints in the layout excerpt that follows; sources: Cadence DE-HDL packaged netlist, KiCad conversion of 04192023_DAF0TMB3IC0_F0TG_MB_C_brd_V02_OCP.brd

C1024  Q_CAP  1UF 4V 20% X6S  pkg 0201  page 312 : A = P0V9_CPU0_RT3_2A ; B = GND
C2621  Q_CAP  22UF 4V 20% X6S  pkg C0402  page 70 : A = PVDD11_S3_P0 ; B = GND
C542  Q_CAP  1UF 4V 20% X6S  pkg 0201  page 279 : A = P0V9_CPU0_RT0_2A_2D ; B = GND

(kicad_pcb
	(version 20260206)
	(generator "pcbnew")
	(generator_version "10.0")
	(general
		(thickness 1.6)
		(legacy_teardrops no)
	)
	(paper "A4")
	(title_block
		(title "04192023_DAF0TMB3IC0_F0TG_MB_C_brd_V02_OCP.brd")
		(comment 1 "Grand Teton / footprints 6536-6538 of 8354")
	)
	(layers
		(0 "F.Cu" signal "TOP")
		(4 "In1.Cu" signal "GND")
		(6 "In2.Cu" signal "IN1")
		(8 "In3.Cu" signal "GND1")
		(10 "In4.Cu" signal "IN2")
		(12 "In5.Cu" signal "GND2")
		(14 "In6.Cu" signal "IN3")
		(16 "In7.Cu" signal "GND3")
		(18 "In8.Cu" signal "VCC")
		(20 "In9.Cu" signal "VCC1")
		(22 "In10.Cu" signal "GND4")
		(24 "In11.Cu" signal "IN4")
		(26 "In12.Cu" signal "GND5")
		(28 "In13.Cu" signal "IN5")
		(30 "In14.Cu" signal "GND6")
		(32 "In15.Cu" signal "IN6")
		(34 "In16.Cu" signal "GND7")
		(2 "B.Cu" signal "BOTTOM")
		(9 "F.Adhes" user "F.Adhesive")
		(11 "B.Adhes" user "B.Adhesive")
		(13 "F.Paste" user "Package Geometry/Pastemask Top")
		(15 "B.Paste" user "Package Geometry/Pastemask Bottom")
		(5 "F.SilkS" user "Ref Des/Silkscreen Top")
		(7 "B.SilkS" user "Ref Des/Silkscreen Bottom")
		(1 "F.Mask" user "Board Geometry/Soldermask Top")
		(3 "B.Mask" user "Board Geometry/Soldermask Bottom")
		(17 "Dwgs.User" user "User.Drawings")
		(19 "Cmts.User" user "User.Comments")
		(21 "Eco1.User" user "User.Eco1")
		(23 "Eco2.User" user "User.Eco2")
		(25 "Edge.Cuts" user "Board Geometry/Outline")
		(27 "Margin" user)
		(31 "F.CrtYd" user "Package Geometry/Place Bound Top")
		(29 "B.CrtYd" user "Package Geometry/Place Bound Bottom")
		(35 "F.Fab" user "Ref Des/Assembly Top")
		(33 "B.Fab" user "Ref Des/Assembly Bottom")
	)
	(footprint ""
		(layer "B.Cu")
		(at 374.0785 -395.148562 90)
		(property "Reference" "C1024"
			(at 0 0 90)
			(layer "B.SilkS")
			(hide yes)
			(effects
				(font
					(size 1.27 1.27)
				)
				(justify mirror)
			)
		)
		(property "Value" ""
			(at 0 0 90)
			(layer "B.Fab")
			(effects
				(font
					(size 1.27 1.27)
				)
				(justify mirror)
			)
		)
		(duplicate_pad_numbers_are_jumpers no)
		(fp_line
			(start 0.299974 -0.150114)
			(end -0.299974 -0.150114)
			(stroke
				(width 0.1)
				(type default)
			)
			(layer "B.Fab")
		)
		(fp_line
			(start -0.299974 -0.150114)
			(end -0.299974 0.150114)
			(stroke
				(width 0.1)
				(type default)
			)
			(layer "B.Fab")
		)
		(fp_line
			(start 0.299974 0.150114)
			(end 0.299974 -0.150114)
			(stroke
				(width 0.1)
				(type default)
			)
			(layer "B.Fab")
		)
		(fp_line
			(start -0.299974 0.150114)
			(end 0.299974 0.150114)
			(stroke
				(width 0.1)
				(type default)
			)
			(layer "B.Fab")
		)
		(pad "1" smd rect
			(at 0.2667 0 270)
			(size 0.3048 0.381)
			(layers "B.Cu" "B.Mask" "B.Paste")
			(net "P0V9_CPU0_RT3_2A")
		)
		(pad "2" smd rect
			(at -0.2667 0 270)
			(size 0.3048 0.381)
			(layers "B.Cu" "B.Mask" "B.Paste")
			(net "GND")
		)
	)
	(footprint ""
		(layer "B.Cu")
		(at 308.1782 -395.148562 90)
		(property "Reference" "C542"
			(at 0 0 90)
			(layer "B.SilkS")
			(hide yes)
			(effects
				(font
					(size 1.27 1.27)
				)
				(justify mirror)
			)
		)
		(property "Value" ""
			(at 0 0 90)
			(layer "B.Fab")
			(effects
				(font
					(size 1.27 1.27)
				)
				(justify mirror)
			)
		)
		(duplicate_pad_numbers_are_jumpers no)
		(fp_line
			(start 0.299974 -0.150114)
			(end -0.299974 -0.150114)
			(stroke
				(width 0.1)
				(type default)
			)
			(layer "B.Fab")
		)
		(fp_line
			(start -0.299974 -0.150114)
			(end -0.299974 0.150114)
			(stroke
				(width 0.1)
				(type default)
			)
			(layer "B.Fab")
		)
		(fp_line
			(start 0.299974 0.150114)
			(end 0.299974 -0.150114)
			(stroke
				(width 0.1)
				(type default)
			)
			(layer "B.Fab")
		)
		(fp_line
			(start -0.299974 0.150114)
			(end 0.299974 0.150114)
			(stroke
				(width 0.1)
				(type default)
			)
			(layer "B.Fab")
		)
		(pad "1" smd rect
			(at 0.2667 0 270)
			(size 0.3048 0.381)
			(layers "B.Cu" "B.Mask" "B.Paste")
			(net "P0V9_CPU0_RT0_2A_2D")
		)
		(pad "2" smd rect
			(at -0.2667 0 270)
			(size 0.3048 0.381)
			(layers "B.Cu" "B.Mask" "B.Paste")
			(net "GND")
		)
	)
	(footprint ""
		(layer "B.Cu")
		(at 358.796082 -259.845048 180)
		(property "Reference" "C2621"
			(at 0 0 0)
			(layer "B.SilkS")
			(hide yes)
			(effects
				(font
					(size 1.27 1.27)
				)
				(justify mirror)
			)
		)
		(property "Value" ""
			(at 0 0 0)
			(layer "B.Fab")
			(effects
				(font
					(size 1.27 1.27)
				)
				(justify mirror)
			)
		)
		(duplicate_pad_numbers_are_jumpers no)
		(fp_line
			(start 0.7874 0.4064)
			(end 0.7874 -0.4064)
			(stroke
				(width 0.1524)
				(type default)
			)
			(layer "B.SilkS")
		)
		(fp_line
			(start 0.7874 -0.4064)
			(end -0.7874 -0.4064)
			(stroke
				(width 0.1524)
				(type default)
			)
			(layer "B.SilkS")
		)
		(fp_line
			(start -0.7874 0.4064)
			(end 0.7874 0.4064)
			(stroke
				(width 0.1524)
				(type default)
			)
			(layer "B.SilkS")
		)
		(fp_line
			(start -0.7874 -0.4064)
			(end -0.7874 0.4064)
			(stroke
				(width 0.1524)
				(type default)
			)
			(layer "B.SilkS")
		)
		(fp_line
			(start 0.67945 0.3048)
			(end 0.67945 -0.305054)
			(stroke
				(width 0.1)
				(type default)
			)
			(layer "B.Fab")
		)
		(fp_line
			(start 0.67945 -0.305054)
			(end 0.12065 -0.305054)
			(stroke
				(width 0.1)
				(type default)
			)
			(layer "B.Fab")
		)
		(fp_line
			(start 0.12065 0.3048)
			(end 0.67945 0.3048)
			(stroke
				(width 0.1)
				(type default)
			)
			(layer "B.Fab")
		)
		(fp_line
			(start 0.12065 0.2794)
			(end 0.12065 0.3048)
			(stroke
				(width 0.1)
				(type default)
			)
			(layer "B.Fab")
		)
		(fp_line
			(start 0.12065 -0.2794)
			(end -0.12065 -0.2794)
			(stroke
				(width 0.1)
				(type default)
			)
			(layer "B.Fab")
		)
		(fp_line
			(start 0.12065 -0.305054)
			(end 0.12065 -0.2794)
			(stroke
				(width 0.1)
				(type default)
			)
			(layer "B.Fab")
		)
		(fp_line
			(start -0.120396 0.3048)
			(end -0.120396 0.2794)
			(stroke
				(width 0.1)
				(type default)
			)
			(layer "B.Fab")
		)
		(fp_line
			(start -0.120396 0.2794)
			(end 0.12065 0.2794)
			(stroke
				(width 0.1)
				(type default)
			)
			(layer "B.Fab")
		)
		(fp_line
			(start -0.12065 -0.2794)
			(end -0.12065 -0.3048)
			(stroke
				(width 0.1)
				(type default)
			)
			(layer "B.Fab")
		)
		(fp_line
			(start -0.12065 -0.3048)
			(end -0.67945 -0.3048)
			(stroke
				(width 0.1)
				(type default)
			)
			(layer "B.Fab")
		)
		(fp_line
			(start -0.67945 0.3048)
			(end -0.120396 0.3048)
			(stroke
				(width 0.1)
				(type default)
			)
			(layer "B.Fab")
		)
		(fp_line
			(start -0.67945 -0.3048)
			(end -0.67945 0.3048)
			(stroke
				(width 0.1)
				(type default)
			)
			(layer "B.Fab")
		)
		(pad "1" smd circle
			(at 0.40005 0)
			(size 0 0)
			(layers "B.Cu" "B.Mask" "B.Paste")
			(net "PVDD11_S3_P0")
		)
		(pad "2" smd circle
			(at -0.40005 0)
			(size 0 0)
			(layers "B.Cu" "B.Mask" "B.Paste")
			(net "GND")
		)
	)
)
